(kicad_pcb
	(version 20260206)
	(generator "pcbnew")
	(generator_version "10.0")
	(general
		(thickness 1.6)
		(legacy_teardrops no)
	)
	(paper "A4")
	(title_block
		(title "01162023_DA0F0TEBIF0_F0T_Expander_BD_F_brd_V02_OCP.brd")
		(comment 1 "Grand Teton / footprints 6220-6224 of 9728")
	)
	(layers
		(0 "F.Cu" signal "TOP")
		(4 "In1.Cu" signal "GND")
		(6 "In2.Cu" signal "VCC")
		(8 "In3.Cu" signal "VCC1")
		(10 "In4.Cu" signal "GND1")
		(12 "In5.Cu" signal "IN1")
		(14 "In6.Cu" signal "GND2")
		(16 "In7.Cu" signal "IN2")
		(18 "In8.Cu" signal "GND3")
		(20 "In9.Cu" signal "IN3")
		(22 "In10.Cu" signal "GND4")
		(24 "In11.Cu" signal "IN4")
		(26 "In12.Cu" signal "GND5")
		(28 "In13.Cu" signal "IN5")
		(30 "In14.Cu" signal "GND6")
		(32 "In15.Cu" signal "IN6")
		(34 "In16.Cu" signal "GND7")
		(2 "B.Cu" signal "BOTTOM")
		(9 "F.Adhes" user "F.Adhesive")
		(11 "B.Adhes" user "B.Adhesive")
		(13 "F.Paste" user "Package Geometry/Pastemask Top")
		(15 "B.Paste" user "Package Geometry/Pastemask Bottom")
		(5 "F.SilkS" user "Ref Des/Silkscreen Top")
		(7 "B.SilkS" user "Ref Des/Silkscreen Bottom")
		(1 "F.Mask" user "Board Geometry/Soldermask Top")
		(3 "B.Mask" user "Board Geometry/Soldermask Bottom")
		(17 "Dwgs.User" user "User.Drawings")
		(19 "Cmts.User" user "User.Comments")
		(21 "Eco1.User" user "User.Eco1")
		(23 "Eco2.User" user "User.Eco2")
		(25 "Edge.Cuts" user "Board Geometry/Outline")
		(27 "Margin" user)
		(31 "F.CrtYd" user "Package Geometry/Place Bound Top")
		(29 "B.CrtYd" user "Package Geometry/Place Bound Bottom")
		(35 "F.Fab" user "Ref Des/Assembly Top")
		(33 "B.Fab" user "Ref Des/Assembly Bottom")
	)
	(footprint ""
		(layer "F.Cu")
		(at 332.679548 -193.669412)
		(property "Reference" "U324"
			(at -1.311148 -4.804918 0)
			(unlocked yes)
			(layer "F.SilkS")
			(effects
				(font
					(size 0.7874 0.5842)
					(thickness 0.1524)
				)
				(justify left)
			)
		)
		(property "Value" ""
			(at 0 0 0)
			(layer "F.Fab")
			(effects
				(font
					(size 1.27 1.27)
				)
			)
		)
		(duplicate_pad_numbers_are_jumpers no)
		(fp_line
			(start -2.097532 -3.949954)
			(end -2.097532 3.949954)
			(stroke
				(width 0.1524)
				(type default)
			)
			(layer "F.SilkS")
		)
		(fp_line
			(start -2.097532 3.949954)
			(end 2.097532 3.949954)
			(stroke
				(width 0.1524)
				(type default)
			)
			(layer "F.SilkS")
		)
		(fp_line
			(start -1.409954 -3.949954)
			(end -2.097532 -3.949954)
			(stroke
				(width 0.1524)
				(type default)
			)
			(layer "F.SilkS")
		)
		(fp_line
			(start 0 -2.54)
			(end -1.409954 -3.949954)
			(stroke
				(width 0.1524)
				(type default)
			)
			(layer "F.SilkS")
		)
		(fp_line
			(start 1.409954 -3.949954)
			(end 0 -2.54)
			(stroke
				(width 0.1524)
				(type default)
			)
			(layer "F.SilkS")
		)
		(fp_line
			(start 2.097532 -3.949954)
			(end 1.409954 -3.949954)
			(stroke
				(width 0.1524)
				(type default)
			)
			(layer "F.SilkS")
		)
		(fp_line
			(start 2.097532 3.949954)
			(end 2.097532 -3.949954)
			(stroke
				(width 0.1524)
				(type default)
			)
			(layer "F.SilkS")
		)
		(fp_poly
			(pts
				(xy -4.132072 -4.97205) (xy -4.850638 -4.253738) (xy -3.772916 -3.894582)
			)
			(stroke
				(width 0)
				(type default)
			)
			(fill yes)
			(layer "F.SilkS")
		)
		(fp_line
			(start -2.249932 -3.949954)
			(end -2.249932 3.949954)
			(stroke
				(width 0.1)
				(type default)
			)
			(layer "F.Fab")
		)
		(fp_line
			(start -2.249932 3.949954)
			(end 2.249932 3.949954)
			(stroke
				(width 0.1)
				(type default)
			)
			(layer "F.Fab")
		)
		(fp_line
			(start 2.249932 -3.949954)
			(end -2.249932 -3.949954)
			(stroke
				(width 0.1)
				(type default)
			)
			(layer "F.Fab")
		)
		(fp_line
			(start 2.249932 3.949954)
			(end 2.249932 -3.949954)
			(stroke
				(width 0.1)
				(type default)
			)
			(layer "F.Fab")
		)
		(fp_poly
			(pts
				(xy -4.7498 -4.182872) (xy -4.7498 -3.166872) (xy -3.7338 -3.674872)
			)
			(stroke
				(width 0)
				(type default)
			)
			(fill yes)
			(layer "F.Fab")
		)
		(pad "1" smd rect
			(at -2.925064 -3.674872 270)
			(size 0.6096 1.3716)
			(layers "F.Cu" "F.Mask" "F.Paste")
			(net "IRQ_IOEXP_DBV2_N")
		)
		(pad "2" smd rect
			(at -2.925064 -2.925064 270)
			(size 0.4064 1.3716)
			(layers "F.Cu" "F.Mask" "F.Paste")
			(net "IOEXP_DBV2_A1")
		)
		(pad "3" smd rect
			(at -2.925064 -2.275078 270)
			(size 0.4064 1.3716)
			(layers "F.Cu" "F.Mask" "F.Paste")
			(net "IOEXP_DBV2_A2")
		)
		(pad "4" smd rect
			(at -2.925064 -1.625092 270)
			(size 0.4064 1.3716)
			(layers "F.Cu" "F.Mask" "F.Paste")
			(net "LED_POSTCODE_0")
		)
		(pad "5" smd rect
			(at -2.925064 -0.975106 270)
			(size 0.4064 1.3716)
			(layers "F.Cu" "F.Mask" "F.Paste")
			(net "LED_POSTCODE_1")
		)
		(pad "6" smd rect
			(at -2.925064 -0.32512 270)
			(size 0.4064 1.3716)
			(layers "F.Cu" "F.Mask" "F.Paste")
			(net "LED_POSTCODE_2")
		)
		(pad "7" smd rect
			(at -2.925064 0.32512 270)
			(size 0.4064 1.3716)
			(layers "F.Cu" "F.Mask" "F.Paste")
			(net "LED_POSTCODE_3")
		)
		(pad "8" smd rect
			(at -2.925064 0.975106 270)
			(size 0.4064 1.3716)
			(layers "F.Cu" "F.Mask" "F.Paste")
			(net "LED_POSTCODE_4")
		)
		(pad "9" smd rect
			(at -2.925064 1.625092 270)
			(size 0.4064 1.3716)
			(layers "F.Cu" "F.Mask" "F.Paste")
			(net "LED_POSTCODE_5")
		)
		(pad "10" smd rect
			(at -2.925064 2.275078 270)
			(size 0.4064 1.3716)
			(layers "F.Cu" "F.Mask" "F.Paste")
			(net "LED_POSTCODE_6")
		)
		(pad "11" smd rect
			(at -2.925064 2.925064 270)
			(size 0.4064 1.3716)
			(layers "F.Cu" "F.Mask" "F.Paste")
			(net "LED_POSTCODE_7")
		)
		(pad "12" smd rect
			(at -2.925064 3.674872 270)
			(size 0.6096 1.3716)
			(layers "F.Cu" "F.Mask" "F.Paste")
			(net "GND")
		)
		(pad "13" smd rect
			(at 2.925064 3.674872 270)
			(size 0.6096 1.3716)
			(layers "F.Cu" "F.Mask" "F.Paste")
			(net "USB_DEBUG_RST_BTN_N")
		)
		(pad "14" smd rect
			(at 2.925064 2.925064 270)
			(size 0.4064 1.3716)
			(layers "F.Cu" "F.Mask" "F.Paste")
			(net "USB_DEBUG_PWR_BTN_N")
		)
		(pad "15" smd rect
			(at 2.925064 2.275078 270)
			(size 0.4064 1.3716)
			(layers "F.Cu" "F.Mask" "F.Paste")
			(net "PWRGD_SYS_PWROK")
		)
		(pad "16" smd rect
			(at 2.925064 1.625092 270)
			(size 0.4064 1.3716)
			(layers "F.Cu" "F.Mask" "F.Paste")
			(net "RST_PLTRST_N")
		)
		(pad "17" smd rect
			(at 2.925064 0.975106 270)
			(size 0.4064 1.3716)
			(layers "F.Cu" "F.Mask" "F.Paste")
			(net "PWRGD_DSW_PWROK")
		)
		(pad "18" smd rect
			(at 2.925064 0.32512 270)
			(size 0.4064 1.3716)
			(layers "F.Cu" "F.Mask" "F.Paste")
			(net "FM_CPU_CATERR_MSMI_LVT3_N")
		)
		(pad "19" smd rect
			(at 2.925064 -0.32512 270)
			(size 0.4064 1.3716)
			(layers "F.Cu" "F.Mask" "F.Paste")
			(net "FM_SLPS3_N")
		)
		(pad "20" smd rect
			(at 2.925064 -0.975106 270)
			(size 0.4064 1.3716)
			(layers "F.Cu" "F.Mask" "F.Paste")
			(net "FM_SOL_UART_CH_SEL")
		)
		(pad "21" smd rect
			(at 2.925064 -1.625092 270)
			(size 0.4064 1.3716)
			(layers "F.Cu" "F.Mask" "F.Paste")
			(net "IOEXP_DBV2_A0")
		)
		(pad "22" smd rect
			(at 2.925064 -2.275078 270)
			(size 0.4064 1.3716)
			(layers "F.Cu" "F.Mask" "F.Paste")
			(net "SMB_IO_DEBUG_CARD_R_SCL")
		)
		(pad "23" smd rect
			(at 2.925064 -2.925064 270)
			(size 0.4064 1.3716)
			(layers "F.Cu" "F.Mask" "F.Paste")
			(net "SMB_IO_DEBUG_CARD_R_SDA")
		)
		(pad "24" smd rect
			(at 2.925064 -3.674872 270)
			(size 0.6096 1.3716)
			(layers "F.Cu" "F.Mask" "F.Paste")
			(net "P3V3_AUX")
		)
	)
	(footprint ""
		(layer "F.Cu")
		(at 295.877742 -117.566186)
		(property "Reference" "R296"
			(at 0 0 0)
			(layer "F.SilkS")
			(hide yes)
			(effects
				(font
					(size 1.27 1.27)
				)
			)
		)
		(property "Value" ""
			(at 0 0 0)
			(layer "F.Fab")
			(effects
				(font
					(size 1.27 1.27)
				)
			)
		)
		(duplicate_pad_numbers_are_jumpers no)
		(fp_line
			(start -0.7874 -0.4064)
			(end 0.7874 -0.4064)
			(stroke
				(width 0.1524)
				(type default)
			)
			(layer "F.SilkS")
		)
		(fp_line
			(start -0.7874 0.4064)
			(end -0.7874 -0.4064)
			(stroke
				(width 0.1524)
				(type default)
			)
			(layer "F.SilkS")
		)
		(fp_line
			(start 0.7874 -0.4064)
			(end 0.7874 0.4064)
			(stroke
				(width 0.1524)
				(type default)
			)
			(layer "F.SilkS")
		)
		(fp_line
			(start 0.7874 0.4064)
			(end -0.7874 0.4064)
			(stroke
				(width 0.1524)
				(type default)
			)
			(layer "F.SilkS")
		)
		(fp_line
			(start -0.67945 -0.305054)
			(end -0.12065 -0.305054)
			(stroke
				(width 0.1)
				(type default)
			)
			(layer "F.Fab")
		)
		(fp_line
			(start -0.67945 0.3048)
			(end -0.67945 -0.305054)
			(stroke
				(width 0.1)
				(type default)
			)
			(layer "F.Fab")
		)
		(fp_line
			(start -0.12065 -0.305054)
			(end -0.12065 -0.2794)
			(stroke
				(width 0.1)
				(type default)
			)
			(layer "F.Fab")
		)
		(fp_line
			(start -0.12065 -0.2794)
			(end 0.12065 -0.2794)
			(stroke
				(width 0.1)
				(type default)
			)
			(layer "F.Fab")
		)
		(fp_line
			(start -0.12065 0.2794)
			(end -0.12065 0.3048)
			(stroke
				(width 0.1)
				(type default)
			)
			(layer "F.Fab")
		)
		(fp_line
			(start -0.12065 0.3048)
			(end -0.67945 0.3048)
			(stroke
				(width 0.1)
				(type default)
			)
			(layer "F.Fab")
		)
		(fp_line
			(start 0.120396 0.2794)
			(end -0.12065 0.2794)
			(stroke
				(width 0.1)
				(type default)
			)
			(layer "F.Fab")
		)
		(fp_line
			(start 0.120396 0.3048)
			(end 0.120396 0.2794)
			(stroke
				(width 0.1)
				(type default)
			)
			(layer "F.Fab")
		)
		(fp_line
			(start 0.12065 -0.3048)
			(end 0.67945 -0.3048)
			(stroke
				(width 0.1)
				(type default)
			)
			(layer "F.Fab")
		)
		(fp_line
			(start 0.12065 -0.2794)
			(end 0.12065 -0.3048)
			(stroke
				(width 0.1)
				(type default)
			)
			(layer "F.Fab")
		)
		(fp_line
			(start 0.67945 -0.3048)
			(end 0.67945 0.3048)
			(stroke
				(width 0.1)
				(type default)
			)
			(layer "F.Fab")
		)
		(fp_line
			(start 0.67945 0.3048)
			(end 0.120396 0.3048)
			(stroke
				(width 0.1)
				(type default)
			)
			(layer "F.Fab")
		)
		(pad "1" smd circle
			(at -0.40005 0)
			(size 0 0)
			(layers "F.Cu" "F.Mask" "F.Paste")
			(net "PRSNT_NIC5_N")
		)
		(pad "2" smd circle
			(at 0.40005 0)
			(size 0 0)
			(layers "F.Cu" "F.Mask" "F.Paste")
			(net "PRSNTB2_NIC5_N")
		)
	)
	(footprint ""
		(layer "F.Cu")
		(at 396.03426 -356.244906 90)
		(property "Reference" "C736"
			(at 0 0 90)
			(layer "F.SilkS")
			(hide yes)
			(effects
				(font
					(size 1.27 1.27)
				)
			)
		)
		(property "Value" ""
			(at 0 0 90)
			(layer "F.Fab")
			(effects
				(font
					(size 1.27 1.27)
				)
			)
		)
		(duplicate_pad_numbers_are_jumpers no)
		(fp_line
			(start 0.299974 -0.150114)
			(end 0.299974 0.150114)
			(stroke
				(width 0.1)
				(type default)
			)
			(layer "F.Fab")
		)
		(fp_line
			(start -0.299974 -0.150114)
			(end 0.299974 -0.150114)
			(stroke
				(width 0.1)
				(type default)
			)
			(layer "F.Fab")
		)
		(fp_line
			(start 0.299974 0.150114)
			(end -0.299974 0.150114)
			(stroke
				(width 0.1)
				(type default)
			)
			(layer "F.Fab")
		)
		(fp_line
			(start -0.299974 0.150114)
			(end -0.299974 -0.150114)
			(stroke
				(width 0.1)
				(type default)
			)
			(layer "F.Fab")
		)
		(pad "1" smd rect
			(at -0.2667 0 90)
			(size 0.3048 0.381)
			(layers "F.Cu" "F.Mask" "F.Paste")
			(net "P5E_PEX3_STN5_TX_DP<92>")
		)
		(pad "2" smd rect
			(at 0.2667 0 90)
			(size 0.3048 0.381)
			(layers "F.Cu" "F.Mask" "F.Paste")
			(net "P5E_PEX3_STN5_TX_C_DP<92>")
		)
	)
	(footprint ""
		(layer "F.Cu")
		(at 98.975672 -118.467886)
		(property "Reference" "PC470"
			(at 0 0 0)
			(layer "F.SilkS")
			(hide yes)
			(effects
				(font
					(size 1.27 1.27)
				)
			)
		)
		(property "Value" ""
			(at 0 0 0)
			(layer "F.Fab")
			(effects
				(font
					(size 1.27 1.27)
				)
			)
		)
		(duplicate_pad_numbers_are_jumpers no)
		(fp_line
			(start -0.7874 -0.4064)
			(end 0.7874 -0.4064)
			(stroke
				(width 0.1524)
				(type default)
			)
			(layer "F.SilkS")
		)
		(fp_line
			(start -0.7874 0.4064)
			(end -0.7874 -0.4064)
			(stroke
				(width 0.1524)
				(type default)
			)
			(layer "F.SilkS")
		)
		(fp_line
			(start 0.7874 -0.4064)
			(end 0.7874 0.4064)
			(stroke
				(width 0.1524)
				(type default)
			)
			(layer "F.SilkS")
		)
		(fp_line
			(start 0.7874 0.4064)
			(end -0.7874 0.4064)
			(stroke
				(width 0.1524)
				(type default)
			)
			(layer "F.SilkS")
		)
		(fp_line
			(start -0.67945 -0.305054)
			(end -0.12065 -0.305054)
			(stroke
				(width 0.1)
				(type default)
			)
			(layer "F.Fab")
		)
		(fp_line
			(start -0.67945 0.3048)
			(end -0.67945 -0.305054)
			(stroke
				(width 0.1)
				(type default)
			)
			(layer "F.Fab")
		)
		(fp_line
			(start -0.12065 -0.305054)
			(end -0.12065 -0.2794)
			(stroke
				(width 0.1)
				(type default)
			)
			(layer "F.Fab")
		)
		(fp_line
			(start -0.12065 -0.2794)
			(end 0.12065 -0.2794)
			(stroke
				(width 0.1)
				(type default)
			)
			(layer "F.Fab")
		)
		(fp_line
			(start -0.12065 0.2794)
			(end -0.12065 0.3048)
			(stroke
				(width 0.1)
				(type default)
			)
			(layer "F.Fab")
		)
		(fp_line
			(start -0.12065 0.3048)
			(end -0.67945 0.3048)
			(stroke
				(width 0.1)
				(type default)
			)
			(layer "F.Fab")
		)
		(fp_line
			(start 0.120396 0.2794)
			(end -0.12065 0.2794)
			(stroke
				(width 0.1)
				(type default)
			)
			(layer "F.Fab")
		)
		(fp_line
			(start 0.120396 0.3048)
			(end 0.120396 0.2794)
			(stroke
				(width 0.1)
				(type default)
			)
			(layer "F.Fab")
		)
		(fp_line
			(start 0.12065 -0.3048)
			(end 0.67945 -0.3048)
			(stroke
				(width 0.1)
				(type default)
			)
			(layer "F.Fab")
		)
		(fp_line
			(start 0.12065 -0.2794)
			(end 0.12065 -0.3048)
			(stroke
				(width 0.1)
				(type default)
			)
			(layer "F.Fab")
		)
		(fp_line
			(start 0.67945 -0.3048)
			(end 0.67945 0.3048)
			(stroke
				(width 0.1)
				(type default)
			)
			(layer "F.Fab")
		)
		(fp_line
			(start 0.67945 0.3048)
			(end 0.120396 0.3048)
			(stroke
				(width 0.1)
				(type default)
			)
			(layer "F.Fab")
		)
		(pad "1" smd circle
			(at -0.40005 0)
			(size 0 0)
			(layers "F.Cu" "F.Mask" "F.Paste")
			(net "P3V3_NIC1_SS")
		)
		(pad "2" smd circle
			(at 0.40005 0)
			(size 0 0)
			(layers "F.Cu" "F.Mask" "F.Paste")
			(net "GND")
		)
	)
	(footprint ""
		(layer "F.Cu")
		(at 322.217542 -304.036476 90)
		(property "Reference" "R1384"
			(at 0 0 90)
			(layer "F.SilkS")
			(hide yes)
			(effects
				(font
					(size 1.27 1.27)
				)
			)
		)
		(property "Value" ""
			(at 0 0 90)
			(layer "F.Fab")
			(effects
				(font
					(size 1.27 1.27)
				)
			)
		)
		(duplicate_pad_numbers_are_jumpers no)
		(fp_line
			(start 0.7874 -0.4064)
			(end 0.7874 0.4064)
			(stroke
				(width 0.1524)
				(type default)
			)
			(layer "F.SilkS")
		)
		(fp_line
			(start -0.7874 -0.4064)
			(end 0.7874 -0.4064)
			(stroke
				(width 0.1524)
				(type default)
			)
			(layer "F.SilkS")
		)
		(fp_line
			(start 0.7874 0.4064)
			(end -0.7874 0.4064)
			(stroke
				(width 0.1524)
				(type default)
			)
			(layer "F.SilkS")
		)
		(fp_line
			(start -0.7874 0.4064)
			(end -0.7874 -0.4064)
			(stroke
				(width 0.1524)
				(type default)
			)
			(layer "F.SilkS")
		)
		(fp_line
			(start -0.12065 -0.305054)
			(end -0.12065 -0.2794)
			(stroke
				(width 0.1)
				(type default)
			)
			(layer "F.Fab")
		)
		(fp_line
			(start -0.67945 -0.305054)
			(end -0.12065 -0.305054)
			(stroke
				(width 0.1)
				(type default)
			)
			(layer "F.Fab")
		)
		(fp_line
			(start 0.67945 -0.3048)
			(end 0.67945 0.3048)
			(stroke
				(width 0.1)
				(type default)
			)
			(layer "F.Fab")
		)
		(fp_line
			(start 0.12065 -0.3048)
			(end 0.67945 -0.3048)
			(stroke
				(width 0.1)
				(type default)
			)
			(layer "F.Fab")
		)
		(fp_line
			(start 0.12065 -0.2794)
			(end 0.12065 -0.3048)
			(stroke
				(width 0.1)
				(type default)
			)
			(layer "F.Fab")
		)
		(fp_line
			(start -0.12065 -0.2794)
			(end 0.12065 -0.2794)
			(stroke
				(width 0.1)
				(type default)
			)
			(layer "F.Fab")
		)
		(fp_line
			(start 0.120396 0.2794)
			(end -0.12065 0.2794)
			(stroke
				(width 0.1)
				(type default)
			)
			(layer "F.Fab")
		)
		(fp_line
			(start -0.12065 0.2794)
			(end -0.12065 0.3048)
			(stroke
				(width 0.1)
				(type default)
			)
			(layer "F.Fab")
		)
		(fp_line
			(start 0.67945 0.3048)
			(end 0.120396 0.3048)
			(stroke
				(width 0.1)
				(type default)
			)
			(layer "F.Fab")
		)
		(fp_line
			(start 0.120396 0.3048)
			(end 0.120396 0.2794)
			(stroke
				(width 0.1)
				(type default)
			)
			(layer "F.Fab")
		)
		(fp_line
			(start -0.12065 0.3048)
			(end -0.67945 0.3048)
			(stroke
				(width 0.1)
				(type default)
			)
			(layer "F.Fab")
		)
		(fp_line
			(start -0.67945 0.3048)
			(end -0.67945 -0.305054)
			(stroke
				(width 0.1)
				(type default)
			)
			(layer "F.Fab")
		)
		(pad "1" smd circle
			(at -0.40005 0 90)
			(size 0 0)
			(layers "F.Cu" "F.Mask" "F.Paste")
			(net "GND")
		)
		(pad "2" smd circle
			(at 0.40005 0 90)
			(size 0 0)
			(layers "F.Cu" "F.Mask" "F.Paste")
			(net "PEX2_SPARE3")
		)
	)
)
